(kicad_pcb
	(version 20260206)
	(generator "pcbnew")
	(generator_version "10.0")
	(general
		(thickness 1.6)
		(legacy_teardrops no)
	)
	(paper "A4")
	(title_block
		(title "01162023_DA0F0TEBIF0_F0T_Expander_BD_F_brd_V02_OCP.brd")
		(comment 1 "Grand Teton / footprints 3667-3673 of 9728")
	)
	(layers
		(0 "F.Cu" signal "TOP")
		(4 "In1.Cu" signal "GND")
		(6 "In2.Cu" signal "VCC")
		(8 "In3.Cu" signal "VCC1")
		(10 "In4.Cu" signal "GND1")
		(12 "In5.Cu" signal "IN1")
		(14 "In6.Cu" signal "GND2")
		(16 "In7.Cu" signal "IN2")
		(18 "In8.Cu" signal "GND3")
		(20 "In9.Cu" signal "IN3")
		(22 "In10.Cu" signal "GND4")
		(24 "In11.Cu" signal "IN4")
		(26 "In12.Cu" signal "GND5")
		(28 "In13.Cu" signal "IN5")
		(30 "In14.Cu" signal "GND6")
		(32 "In15.Cu" signal "IN6")
		(34 "In16.Cu" signal "GND7")
		(2 "B.Cu" signal "BOTTOM")
		(9 "F.Adhes" user "F.Adhesive")
		(11 "B.Adhes" user "B.Adhesive")
		(13 "F.Paste" user "Package Geometry/Pastemask Top")
		(15 "B.Paste" user "Package Geometry/Pastemask Bottom")
		(5 "F.SilkS" user "Ref Des/Silkscreen Top")
		(7 "B.SilkS" user "Ref Des/Silkscreen Bottom")
		(1 "F.Mask" user "Board Geometry/Soldermask Top")
		(3 "B.Mask" user "Board Geometry/Soldermask Bottom")
		(17 "Dwgs.User" user "User.Drawings")
		(19 "Cmts.User" user "User.Comments")
		(21 "Eco1.User" user "User.Eco1")
		(23 "Eco2.User" user "User.Eco2")
		(25 "Edge.Cuts" user "Board Geometry/Outline")
		(27 "Margin" user)
		(31 "F.CrtYd" user "Package Geometry/Place Bound Top")
		(29 "B.CrtYd" user "Package Geometry/Place Bound Bottom")
		(35 "F.Fab" user "Ref Des/Assembly Top")
		(33 "B.Fab" user "Ref Des/Assembly Bottom")
	)
	(footprint ""
		(layer "F.Cu")
		(at 177.705512 -356.244906 90)
		(property "Reference" "C2528"
			(at 0 0 90)
			(layer "F.SilkS")
			(hide yes)
			(effects
				(font
					(size 1.27 1.27)
				)
			)
		)
		(property "Value" ""
			(at 0 0 90)
			(layer "F.Fab")
			(effects
				(font
					(size 1.27 1.27)
				)
			)
		)
		(duplicate_pad_numbers_are_jumpers no)
		(fp_line
			(start 0.299974 -0.150114)
			(end 0.299974 0.150114)
			(stroke
				(width 0.1)
				(type default)
			)
			(layer "F.Fab")
		)
		(fp_line
			(start -0.299974 -0.150114)
			(end 0.299974 -0.150114)
			(stroke
				(width 0.1)
				(type default)
			)
			(layer "F.Fab")
		)
		(fp_line
			(start 0.299974 0.150114)
			(end -0.299974 0.150114)
			(stroke
				(width 0.1)
				(type default)
			)
			(layer "F.Fab")
		)
		(fp_line
			(start -0.299974 0.150114)
			(end -0.299974 -0.150114)
			(stroke
				(width 0.1)
				(type default)
			)
			(layer "F.Fab")
		)
		(pad "1" smd rect
			(at -0.2667 0 90)
			(size 0.3048 0.381)
			(layers "F.Cu" "F.Mask" "F.Paste")
			(net "P5E_PEX1_STN4_TX_DP<71>")
		)
		(pad "2" smd rect
			(at 0.2667 0 90)
			(size 0.3048 0.381)
			(layers "F.Cu" "F.Mask" "F.Paste")
			(net "P5E_PEX1_STN4_TX_C_DP<71>")
		)
	)
	(footprint ""
		(layer "F.Cu")
		(at 98.048318 -395.1478 180)
		(property "Reference" "R5460"
			(at 0 0 180)
			(layer "F.SilkS")
			(hide yes)
			(effects
				(font
					(size 1.27 1.27)
				)
			)
		)
		(property "Value" ""
			(at 0 0 180)
			(layer "F.Fab")
			(effects
				(font
					(size 1.27 1.27)
				)
			)
		)
		(duplicate_pad_numbers_are_jumpers no)
		(fp_line
			(start 0.7874 0.4064)
			(end -0.7874 0.4064)
			(stroke
				(width 0.1524)
				(type default)
			)
			(layer "F.SilkS")
		)
		(fp_line
			(start 0.7874 -0.4064)
			(end 0.7874 0.4064)
			(stroke
				(width 0.1524)
				(type default)
			)
			(layer "F.SilkS")
		)
		(fp_line
			(start -0.7874 0.4064)
			(end -0.7874 -0.4064)
			(stroke
				(width 0.1524)
				(type default)
			)
			(layer "F.SilkS")
		)
		(fp_line
			(start -0.7874 -0.4064)
			(end 0.7874 -0.4064)
			(stroke
				(width 0.1524)
				(type default)
			)
			(layer "F.SilkS")
		)
		(fp_line
			(start 0.67945 0.3048)
			(end 0.120396 0.3048)
			(stroke
				(width 0.1)
				(type default)
			)
			(layer "F.Fab")
		)
		(fp_line
			(start 0.67945 -0.3048)
			(end 0.67945 0.3048)
			(stroke
				(width 0.1)
				(type default)
			)
			(layer "F.Fab")
		)
		(fp_line
			(start 0.12065 -0.2794)
			(end 0.12065 -0.3048)
			(stroke
				(width 0.1)
				(type default)
			)
			(layer "F.Fab")
		)
		(fp_line
			(start 0.12065 -0.3048)
			(end 0.67945 -0.3048)
			(stroke
				(width 0.1)
				(type default)
			)
			(layer "F.Fab")
		)
		(fp_line
			(start 0.120396 0.3048)
			(end 0.120396 0.2794)
			(stroke
				(width 0.1)
				(type default)
			)
			(layer "F.Fab")
		)
		(fp_line
			(start 0.120396 0.2794)
			(end -0.12065 0.2794)
			(stroke
				(width 0.1)
				(type default)
			)
			(layer "F.Fab")
		)
		(fp_line
			(start -0.12065 0.3048)
			(end -0.67945 0.3048)
			(stroke
				(width 0.1)
				(type default)
			)
			(layer "F.Fab")
		)
		(fp_line
			(start -0.12065 0.2794)
			(end -0.12065 0.3048)
			(stroke
				(width 0.1)
				(type default)
			)
			(layer "F.Fab")
		)
		(fp_line
			(start -0.12065 -0.2794)
			(end 0.12065 -0.2794)
			(stroke
				(width 0.1)
				(type default)
			)
			(layer "F.Fab")
		)
		(fp_line
			(start -0.12065 -0.305054)
			(end -0.12065 -0.2794)
			(stroke
				(width 0.1)
				(type default)
			)
			(layer "F.Fab")
		)
		(fp_line
			(start -0.67945 0.3048)
			(end -0.67945 -0.305054)
			(stroke
				(width 0.1)
				(type default)
			)
			(layer "F.Fab")
		)
		(fp_line
			(start -0.67945 -0.305054)
			(end -0.12065 -0.305054)
			(stroke
				(width 0.1)
				(type default)
			)
			(layer "F.Fab")
		)
		(pad "1" smd circle
			(at -0.40005 0 180)
			(size 0 0)
			(layers "F.Cu" "F.Mask" "F.Paste")
			(net "BIC_USB_HUB_PSELF")
		)
		(pad "2" smd circle
			(at 0.40005 0 180)
			(size 0 0)
			(layers "F.Cu" "F.Mask" "F.Paste")
			(net "GND")
		)
	)
	(footprint ""
		(layer "F.Cu")
		(at 427.614842 -81.36001 -90)
		(property "Reference" "R408"
			(at 0 0 270)
			(layer "F.SilkS")
			(hide yes)
			(effects
				(font
					(size 1.27 1.27)
				)
			)
		)
		(property "Value" ""
			(at 0 0 270)
			(layer "F.Fab")
			(effects
				(font
					(size 1.27 1.27)
				)
			)
		)
		(duplicate_pad_numbers_are_jumpers no)
		(fp_line
			(start -0.7874 0.4064)
			(end -0.7874 -0.4064)
			(stroke
				(width 0.1524)
				(type default)
			)
			(layer "F.SilkS")
		)
		(fp_line
			(start 0.7874 0.4064)
			(end -0.7874 0.4064)
			(stroke
				(width 0.1524)
				(type default)
			)
			(layer "F.SilkS")
		)
		(fp_line
			(start -0.7874 -0.4064)
			(end 0.7874 -0.4064)
			(stroke
				(width 0.1524)
				(type default)
			)
			(layer "F.SilkS")
		)
		(fp_line
			(start 0.7874 -0.4064)
			(end 0.7874 0.4064)
			(stroke
				(width 0.1524)
				(type default)
			)
			(layer "F.SilkS")
		)
		(fp_line
			(start -0.67945 0.3048)
			(end -0.67945 -0.305054)
			(stroke
				(width 0.1)
				(type default)
			)
			(layer "F.Fab")
		)
		(fp_line
			(start -0.12065 0.3048)
			(end -0.67945 0.3048)
			(stroke
				(width 0.1)
				(type default)
			)
			(layer "F.Fab")
		)
		(fp_line
			(start 0.120396 0.3048)
			(end 0.120396 0.2794)
			(stroke
				(width 0.1)
				(type default)
			)
			(layer "F.Fab")
		)
		(fp_line
			(start 0.67945 0.3048)
			(end 0.120396 0.3048)
			(stroke
				(width 0.1)
				(type default)
			)
			(layer "F.Fab")
		)
		(fp_line
			(start -0.12065 0.2794)
			(end -0.12065 0.3048)
			(stroke
				(width 0.1)
				(type default)
			)
			(layer "F.Fab")
		)
		(fp_line
			(start 0.120396 0.2794)
			(end -0.12065 0.2794)
			(stroke
				(width 0.1)
				(type default)
			)
			(layer "F.Fab")
		)
		(fp_line
			(start -0.12065 -0.2794)
			(end 0.12065 -0.2794)
			(stroke
				(width 0.1)
				(type default)
			)
			(layer "F.Fab")
		)
		(fp_line
			(start 0.12065 -0.2794)
			(end 0.12065 -0.3048)
			(stroke
				(width 0.1)
				(type default)
			)
			(layer "F.Fab")
		)
		(fp_line
			(start 0.12065 -0.3048)
			(end 0.67945 -0.3048)
			(stroke
				(width 0.1)
				(type default)
			)
			(layer "F.Fab")
		)
		(fp_line
			(start 0.67945 -0.3048)
			(end 0.67945 0.3048)
			(stroke
				(width 0.1)
				(type default)
			)
			(layer "F.Fab")
		)
		(fp_line
			(start -0.67945 -0.305054)
			(end -0.12065 -0.305054)
			(stroke
				(width 0.1)
				(type default)
			)
			(layer "F.Fab")
		)
		(fp_line
			(start -0.12065 -0.305054)
			(end -0.12065 -0.2794)
			(stroke
				(width 0.1)
				(type default)
			)
			(layer "F.Fab")
		)
		(pad "1" smd circle
			(at -0.40005 0 270)
			(size 0 0)
			(layers "F.Cu" "F.Mask" "F.Paste")
			(net "HP_NIC7_PWRGD_R")
		)
		(pad "2" smd circle
			(at 0.40005 0 270)
			(size 0 0)
			(layers "F.Cu" "F.Mask" "F.Paste")
			(net "HP_NIC7_PWRGD")
		)
	)
	(footprint ""
		(layer "F.Cu")
		(at 375.690384 -252.356874 -90)
		(property "Reference" "R1430"
			(at 0 0 270)
			(layer "F.SilkS")
			(hide yes)
			(effects
				(font
					(size 1.27 1.27)
				)
			)
		)
		(property "Value" ""
			(at 0 0 270)
			(layer "F.Fab")
			(effects
				(font
					(size 1.27 1.27)
				)
			)
		)
		(duplicate_pad_numbers_are_jumpers no)
		(fp_line
			(start -0.7874 0.4064)
			(end -0.7874 -0.4064)
			(stroke
				(width 0.1524)
				(type default)
			)
			(layer "F.SilkS")
		)
		(fp_line
			(start 0.7874 0.4064)
			(end -0.7874 0.4064)
			(stroke
				(width 0.1524)
				(type default)
			)
			(layer "F.SilkS")
		)
		(fp_line
			(start -0.7874 -0.4064)
			(end 0.7874 -0.4064)
			(stroke
				(width 0.1524)
				(type default)
			)
			(layer "F.SilkS")
		)
		(fp_line
			(start 0.7874 -0.4064)
			(end 0.7874 0.4064)
			(stroke
				(width 0.1524)
				(type default)
			)
			(layer "F.SilkS")
		)
		(fp_line
			(start -0.67945 0.3048)
			(end -0.67945 -0.305054)
			(stroke
				(width 0.1)
				(type default)
			)
			(layer "F.Fab")
		)
		(fp_line
			(start -0.12065 0.3048)
			(end -0.67945 0.3048)
			(stroke
				(width 0.1)
				(type default)
			)
			(layer "F.Fab")
		)
		(fp_line
			(start 0.120396 0.3048)
			(end 0.120396 0.2794)
			(stroke
				(width 0.1)
				(type default)
			)
			(layer "F.Fab")
		)
		(fp_line
			(start 0.67945 0.3048)
			(end 0.120396 0.3048)
			(stroke
				(width 0.1)
				(type default)
			)
			(layer "F.Fab")
		)
		(fp_line
			(start -0.12065 0.2794)
			(end -0.12065 0.3048)
			(stroke
				(width 0.1)
				(type default)
			)
			(layer "F.Fab")
		)
		(fp_line
			(start 0.120396 0.2794)
			(end -0.12065 0.2794)
			(stroke
				(width 0.1)
				(type default)
			)
			(layer "F.Fab")
		)
		(fp_line
			(start -0.12065 -0.2794)
			(end 0.12065 -0.2794)
			(stroke
				(width 0.1)
				(type default)
			)
			(layer "F.Fab")
		)
		(fp_line
			(start 0.12065 -0.2794)
			(end 0.12065 -0.3048)
			(stroke
				(width 0.1)
				(type default)
			)
			(layer "F.Fab")
		)
		(fp_line
			(start 0.12065 -0.3048)
			(end 0.67945 -0.3048)
			(stroke
				(width 0.1)
				(type default)
			)
			(layer "F.Fab")
		)
		(fp_line
			(start 0.67945 -0.3048)
			(end 0.67945 0.3048)
			(stroke
				(width 0.1)
				(type default)
			)
			(layer "F.Fab")
		)
		(fp_line
			(start -0.67945 -0.305054)
			(end -0.12065 -0.305054)
			(stroke
				(width 0.1)
				(type default)
			)
			(layer "F.Fab")
		)
		(fp_line
			(start -0.12065 -0.305054)
			(end -0.12065 -0.2794)
			(stroke
				(width 0.1)
				(type default)
			)
			(layer "F.Fab")
		)
		(pad "1" smd circle
			(at -0.40005 0 270)
			(size 0 0)
			(layers "F.Cu" "F.Mask" "F.Paste")
			(net "GND")
		)
		(pad "2" smd circle
			(at 0.40005 0 270)
			(size 0 0)
			(layers "F.Cu" "F.Mask" "F.Paste")
			(net "PEX3_MODE_SEL5")
		)
	)
	(footprint ""
		(layer "F.Cu")
		(at 355.854 -178.562 180)
		(property "Reference" "R4728"
			(at 0 0 180)
			(layer "F.SilkS")
			(hide yes)
			(effects
				(font
					(size 1.27 1.27)
				)
			)
		)
		(property "Value" ""
			(at 0 0 180)
			(layer "F.Fab")
			(effects
				(font
					(size 1.27 1.27)
				)
			)
		)
		(duplicate_pad_numbers_are_jumpers no)
		(fp_line
			(start 0.7874 0.4064)
			(end -0.7874 0.4064)
			(stroke
				(width 0.1524)
				(type default)
			)
			(layer "F.SilkS")
		)
		(fp_line
			(start 0.7874 -0.4064)
			(end 0.7874 0.4064)
			(stroke
				(width 0.1524)
				(type default)
			)
			(layer "F.SilkS")
		)
		(fp_line
			(start -0.7874 0.4064)
			(end -0.7874 -0.4064)
			(stroke
				(width 0.1524)
				(type default)
			)
			(layer "F.SilkS")
		)
		(fp_line
			(start -0.7874 -0.4064)
			(end 0.7874 -0.4064)
			(stroke
				(width 0.1524)
				(type default)
			)
			(layer "F.SilkS")
		)
		(fp_line
			(start 0.67945 0.3048)
			(end 0.120396 0.3048)
			(stroke
				(width 0.1)
				(type default)
			)
			(layer "F.Fab")
		)
		(fp_line
			(start 0.67945 -0.3048)
			(end 0.67945 0.3048)
			(stroke
				(width 0.1)
				(type default)
			)
			(layer "F.Fab")
		)
		(fp_line
			(start 0.12065 -0.2794)
			(end 0.12065 -0.3048)
			(stroke
				(width 0.1)
				(type default)
			)
			(layer "F.Fab")
		)
		(fp_line
			(start 0.12065 -0.3048)
			(end 0.67945 -0.3048)
			(stroke
				(width 0.1)
				(type default)
			)
			(layer "F.Fab")
		)
		(fp_line
			(start 0.120396 0.3048)
			(end 0.120396 0.2794)
			(stroke
				(width 0.1)
				(type default)
			)
			(layer "F.Fab")
		)
		(fp_line
			(start 0.120396 0.2794)
			(end -0.12065 0.2794)
			(stroke
				(width 0.1)
				(type default)
			)
			(layer "F.Fab")
		)
		(fp_line
			(start -0.12065 0.3048)
			(end -0.67945 0.3048)
			(stroke
				(width 0.1)
				(type default)
			)
			(layer "F.Fab")
		)
		(fp_line
			(start -0.12065 0.2794)
			(end -0.12065 0.3048)
			(stroke
				(width 0.1)
				(type default)
			)
			(layer "F.Fab")
		)
		(fp_line
			(start -0.12065 -0.2794)
			(end 0.12065 -0.2794)
			(stroke
				(width 0.1)
				(type default)
			)
			(layer "F.Fab")
		)
		(fp_line
			(start -0.12065 -0.305054)
			(end -0.12065 -0.2794)
			(stroke
				(width 0.1)
				(type default)
			)
			(layer "F.Fab")
		)
		(fp_line
			(start -0.67945 0.3048)
			(end -0.67945 -0.305054)
			(stroke
				(width 0.1)
				(type default)
			)
			(layer "F.Fab")
		)
		(fp_line
			(start -0.67945 -0.305054)
			(end -0.12065 -0.305054)
			(stroke
				(width 0.1)
				(type default)
			)
			(layer "F.Fab")
		)
		(pad "1" smd circle
			(at -0.40005 0 180)
			(size 0 0)
			(layers "F.Cu" "F.Mask" "F.Paste")
			(net "P3V3_AUX")
		)
		(pad "2" smd circle
			(at 0.40005 0 180)
			(size 0 0)
			(layers "F.Cu" "F.Mask" "F.Paste")
			(net "NIC4_PEX_PWR_EN_R")
		)
	)
	(footprint ""
		(layer "F.Cu")
		(at 242.838478 -215.05291 180)
		(property "Reference" "R474"
			(at 0 0 180)
			(layer "F.SilkS")
			(hide yes)
			(effects
				(font
					(size 1.27 1.27)
				)
			)
		)
		(property "Value" ""
			(at 0 0 180)
			(layer "F.Fab")
			(effects
				(font
					(size 1.27 1.27)
				)
			)
		)
		(duplicate_pad_numbers_are_jumpers no)
		(fp_line
			(start 0.7874 0.4064)
			(end -0.7874 0.4064)
			(stroke
				(width 0.1524)
				(type default)
			)
			(layer "F.SilkS")
		)
		(fp_line
			(start 0.7874 -0.4064)
			(end 0.7874 0.4064)
			(stroke
				(width 0.1524)
				(type default)
			)
			(layer "F.SilkS")
		)
		(fp_line
			(start -0.7874 0.4064)
			(end -0.7874 -0.4064)
			(stroke
				(width 0.1524)
				(type default)
			)
			(layer "F.SilkS")
		)
		(fp_line
			(start -0.7874 -0.4064)
			(end 0.7874 -0.4064)
			(stroke
				(width 0.1524)
				(type default)
			)
			(layer "F.SilkS")
		)
		(fp_line
			(start 0.67945 0.3048)
			(end 0.120396 0.3048)
			(stroke
				(width 0.1)
				(type default)
			)
			(layer "F.Fab")
		)
		(fp_line
			(start 0.67945 -0.3048)
			(end 0.67945 0.3048)
			(stroke
				(width 0.1)
				(type default)
			)
			(layer "F.Fab")
		)
		(fp_line
			(start 0.12065 -0.2794)
			(end 0.12065 -0.3048)
			(stroke
				(width 0.1)
				(type default)
			)
			(layer "F.Fab")
		)
		(fp_line
			(start 0.12065 -0.3048)
			(end 0.67945 -0.3048)
			(stroke
				(width 0.1)
				(type default)
			)
			(layer "F.Fab")
		)
		(fp_line
			(start 0.120396 0.3048)
			(end 0.120396 0.2794)
			(stroke
				(width 0.1)
				(type default)
			)
			(layer "F.Fab")
		)
		(fp_line
			(start 0.120396 0.2794)
			(end -0.12065 0.2794)
			(stroke
				(width 0.1)
				(type default)
			)
			(layer "F.Fab")
		)
		(fp_line
			(start -0.12065 0.3048)
			(end -0.67945 0.3048)
			(stroke
				(width 0.1)
				(type default)
			)
			(layer "F.Fab")
		)
		(fp_line
			(start -0.12065 0.2794)
			(end -0.12065 0.3048)
			(stroke
				(width 0.1)
				(type default)
			)
			(layer "F.Fab")
		)
		(fp_line
			(start -0.12065 -0.2794)
			(end 0.12065 -0.2794)
			(stroke
				(width 0.1)
				(type default)
			)
			(layer "F.Fab")
		)
		(fp_line
			(start -0.12065 -0.305054)
			(end -0.12065 -0.2794)
			(stroke
				(width 0.1)
				(type default)
			)
			(layer "F.Fab")
		)
		(fp_line
			(start -0.67945 0.3048)
			(end -0.67945 -0.305054)
			(stroke
				(width 0.1)
				(type default)
			)
			(layer "F.Fab")
		)
		(fp_line
			(start -0.67945 -0.305054)
			(end -0.12065 -0.305054)
			(stroke
				(width 0.1)
				(type default)
			)
			(layer "F.Fab")
		)
		(pad "1" smd circle
			(at -0.40005 0 180)
			(size 0 0)
			(layers "F.Cu" "F.Mask" "F.Paste")
			(net "P3V3_AUX")
		)
		(pad "2" smd circle
			(at 0.40005 0 180)
			(size 0 0)
			(layers "F.Cu" "F.Mask" "F.Paste")
			(net "P3V3_AUX_SCALED")
		)
	)
	(footprint ""
		(layer "F.Cu")
		(at 353.201986 -32.849312 90)
		(property "Reference" "R5702"
			(at 0 0 90)
			(layer "F.SilkS")
			(hide yes)
			(effects
				(font
					(size 1.27 1.27)
				)
			)
		)
		(property "Value" ""
			(at 0 0 90)
			(layer "F.Fab")
			(effects
				(font
					(size 1.27 1.27)
				)
			)
		)
		(duplicate_pad_numbers_are_jumpers no)
		(fp_line
			(start 0.7874 -0.4064)
			(end 0.7874 0.4064)
			(stroke
				(width 0.1524)
				(type default)
			)
			(layer "F.SilkS")
		)
		(fp_line
			(start -0.7874 -0.4064)
			(end 0.7874 -0.4064)
			(stroke
				(width 0.1524)
				(type default)
			)
			(layer "F.SilkS")
		)
		(fp_line
			(start 0.7874 0.4064)
			(end -0.7874 0.4064)
			(stroke
				(width 0.1524)
				(type default)
			)
			(layer "F.SilkS")
		)
		(fp_line
			(start -0.7874 0.4064)
			(end -0.7874 -0.4064)
			(stroke
				(width 0.1524)
				(type default)
			)
			(layer "F.SilkS")
		)
		(fp_line
			(start -0.12065 -0.305054)
			(end -0.12065 -0.2794)
			(stroke
				(width 0.1)
				(type default)
			)
			(layer "F.Fab")
		)
		(fp_line
			(start -0.67945 -0.305054)
			(end -0.12065 -0.305054)
			(stroke
				(width 0.1)
				(type default)
			)
			(layer "F.Fab")
		)
		(fp_line
			(start 0.67945 -0.3048)
			(end 0.67945 0.3048)
			(stroke
				(width 0.1)
				(type default)
			)
			(layer "F.Fab")
		)
		(fp_line
			(start 0.12065 -0.3048)
			(end 0.67945 -0.3048)
			(stroke
				(width 0.1)
				(type default)
			)
			(layer "F.Fab")
		)
		(fp_line
			(start 0.12065 -0.2794)
			(end 0.12065 -0.3048)
			(stroke
				(width 0.1)
				(type default)
			)
			(layer "F.Fab")
		)
		(fp_line
			(start -0.12065 -0.2794)
			(end 0.12065 -0.2794)
			(stroke
				(width 0.1)
				(type default)
			)
			(layer "F.Fab")
		)
		(fp_line
			(start 0.120396 0.2794)
			(end -0.12065 0.2794)
			(stroke
				(width 0.1)
				(type default)
			)
			(layer "F.Fab")
		)
		(fp_line
			(start -0.12065 0.2794)
			(end -0.12065 0.3048)
			(stroke
				(width 0.1)
				(type default)
			)
			(layer "F.Fab")
		)
		(fp_line
			(start 0.67945 0.3048)
			(end 0.120396 0.3048)
			(stroke
				(width 0.1)
				(type default)
			)
			(layer "F.Fab")
		)
		(fp_line
			(start 0.120396 0.3048)
			(end 0.120396 0.2794)
			(stroke
				(width 0.1)
				(type default)
			)
			(layer "F.Fab")
		)
		(fp_line
			(start -0.12065 0.3048)
			(end -0.67945 0.3048)
			(stroke
				(width 0.1)
				(type default)
			)
			(layer "F.Fab")
		)
		(fp_line
			(start -0.67945 0.3048)
			(end -0.67945 -0.305054)
			(stroke
				(width 0.1)
				(type default)
			)
			(layer "F.Fab")
		)
		(pad "1" smd circle
			(at -0.40005 0 90)
			(size 0 0)
			(layers "F.Cu" "F.Mask" "F.Paste")
			(net "RST_SMB_SSD12_ISO_R_N")
		)
		(pad "2" smd circle
			(at 0.40005 0 90)
			(size 0 0)
			(layers "F.Cu" "F.Mask" "F.Paste")
			(net "RST_SMB_SSD12_ISO_N")
		)
	)
)
